(kicad_pcb
	(version 20260206)
	(generator "pcbnew")
	(generator_version "10.0")
	(general
		(thickness 1.6)
		(legacy_teardrops no)
	)
	(paper "A4")
	(title_block
		(title "04192023_DAF0TMB3IC0_F0TG_MB_C_brd_V02_OCP.brd")
		(comment 1 "Grand Teton / footprint 1872 of 8354 (J45), pads 1-62 of 62")
	)
	(layers
		(0 "F.Cu" signal "TOP")
		(4 "In1.Cu" signal "GND")
		(6 "In2.Cu" signal "IN1")
		(8 "In3.Cu" signal "GND1")
		(10 "In4.Cu" signal "IN2")
		(12 "In5.Cu" signal "GND2")
		(14 "In6.Cu" signal "IN3")
		(16 "In7.Cu" signal "GND3")
		(18 "In8.Cu" signal "VCC")
		(20 "In9.Cu" signal "VCC1")
		(22 "In10.Cu" signal "GND4")
		(24 "In11.Cu" signal "IN4")
		(26 "In12.Cu" signal "GND5")
		(28 "In13.Cu" signal "IN5")
		(30 "In14.Cu" signal "GND6")
		(32 "In15.Cu" signal "IN6")
		(34 "In16.Cu" signal "GND7")
		(2 "B.Cu" signal "BOTTOM")
		(9 "F.Adhes" user "F.Adhesive")
		(11 "B.Adhes" user "B.Adhesive")
		(13 "F.Paste" user "Package Geometry/Pastemask Top")
		(15 "B.Paste" user "Package Geometry/Pastemask Bottom")
		(5 "F.SilkS" user "Ref Des/Silkscreen Top")
		(7 "B.SilkS" user "Ref Des/Silkscreen Bottom")
		(1 "F.Mask" user "Board Geometry/Soldermask Top")
		(3 "B.Mask" user "Board Geometry/Soldermask Bottom")
		(17 "Dwgs.User" user "User.Drawings")
		(19 "Cmts.User" user "User.Comments")
		(21 "Eco1.User" user "User.Eco1")
		(23 "Eco2.User" user "User.Eco2")
		(25 "Edge.Cuts" user "Board Geometry/Outline")
		(27 "Margin" user)
		(31 "F.CrtYd" user "Package Geometry/Place Bound Top")
		(29 "B.CrtYd" user "Package Geometry/Place Bound Bottom")
		(35 "F.Fab" user "Ref Des/Assembly Top")
		(33 "B.Fab" user "Ref Des/Assembly Bottom")
	)
	(footprint ""
		(layer "F.Cu")
		(at 238.45012 -435.58206 -90)
		(property "Reference" "J45"
			(at 11.30173 -38.15588 0)
			(unlocked yes)
			(layer "F.SilkS")
			(effects
				(font
					(size 0.7874 0.5842)
					(thickness 0.1524)
				)
				(justify left)
			)
		)
		(property "Value" ""
			(at 0 0 270)
			(layer "F.Fab")
			(effects
				(font
					(size 1.27 1.27)
				)
			)
		)
		(duplicate_pad_numbers_are_jumpers no)
		(pad "" np_thru_hole circle
			(at 2.54 -32.385 270)
			(size 0 0)
			(drill 3.048)
			(layers "*.Cu" "*.Mask")
			(clearance 0)
		)
		(pad "" np_thru_hole circle
			(at 2.54 37.465 270)
			(size 0 0)
			(drill 3.048)
			(layers "*.Cu" "*.Mask")
			(clearance 0)
		)
		(pad "A1" thru_hole rect
			(at 0 0 270)
			(size 1.669796 1.669796)
			(drill 1.01981)
			(layers "*.Cu" "*.Mask")
			(remove_unused_layers no)
			(net "TP_J45_A1")
			(clearance -0.070866)
			(padstack
				(mode front_inner_back)
				(layer "Inner"
					(shape circle)
					(size 1.669796 1.669796)
					(clearance -0.070866)
				)
				(layer "B.Cu"
					(shape rect)
					(size 1.669796 1.669796)
					(clearance -0.070866)
				)
			)
		)
		(pad "A2" thru_hole circle
			(at 0 2.54 270)
			(size 1.669796 1.669796)
			(drill 1.01981)
			(layers "*.Cu" "*.Mask")
			(remove_unused_layers no)
			(net "FM_AC_PWR_BTN_PDB_N")
			(clearance -0.070866)
		)
		(pad "A3" thru_hole circle
			(at 0 5.08 270)
			(size 1.669796 1.669796)
			(drill 1.01981)
			(layers "*.Cu" "*.Mask")
			(remove_unused_layers no)
			(net "P3V3_PDB_AUX_ADC")
			(clearance -0.070866)
		)
		(pad "B1" thru_hole circle
			(at 2.54 0 270)
			(size 1.669796 1.669796)
			(drill 1.01981)
			(layers "*.Cu" "*.Mask")
			(remove_unused_layers no)
			(net "RST_SMB_SWITCH_R_N")
			(clearance -0.070866)
		)
		(pad "B2" thru_hole circle
			(at 2.54 2.54 270)
			(size 1.669796 1.669796)
			(drill 1.01981)
			(layers "*.Cu" "*.Mask")
			(remove_unused_layers no)
			(net "PWRGD_P3V3_AUX_PDB_BUF")
			(clearance -0.070866)
		)
		(pad "B3" thru_hole circle
			(at 2.54 5.08 270)
			(size 1.669796 1.669796)
			(drill 1.01981)
			(layers "*.Cu" "*.Mask")
			(remove_unused_layers no)
			(net "GND")
			(clearance -0.070866)
		)
		(pad "C1" thru_hole circle
			(at 5.08 0 270)
			(size 1.669796 1.669796)
			(drill 1.01981)
			(layers "*.Cu" "*.Mask")
			(remove_unused_layers no)
			(net "SMB_FAN_3V3AUX_BUF_R_SCL")
			(clearance -0.070866)
		)
		(pad "C2" thru_hole circle
			(at 5.08 2.54 270)
			(size 1.669796 1.669796)
			(drill 1.01981)
			(layers "*.Cu" "*.Mask")
			(remove_unused_layers no)
			(net "SMB_FAN_3V3AUX_BUF_R_SDA")
			(clearance -0.070866)
		)
		(pad "C3" thru_hole circle
			(at 5.08 5.08 270)
			(size 1.669796 1.669796)
			(drill 1.01981)
			(layers "*.Cu" "*.Mask")
			(remove_unused_layers no)
			(net "HPDB_HSC_PWRGD_R")
			(clearance -0.070866)
		)
		(pad "D1" thru_hole circle
			(at 7.62 0 270)
			(size 1.669796 1.669796)
			(drill 1.01981)
			(layers "*.Cu" "*.Mask")
			(remove_unused_layers no)
			(net "FM_FAN_PWR_EN_R")
			(clearance -0.070866)
		)
		(pad "D2" thru_hole circle
			(at 7.62 2.54 270)
			(size 1.669796 1.669796)
			(drill 1.01981)
			(layers "*.Cu" "*.Mask")
			(remove_unused_layers no)
			(net "FM_GPU_HSC_EN_BUF_R1")
			(clearance -0.070866)
		)
		(pad "D3" thru_hole circle
			(at 7.62 5.08 270)
			(size 1.669796 1.669796)
			(drill 1.01981)
			(layers "*.Cu" "*.Mask")
			(remove_unused_layers no)
			(net "PDB_PRSNT_N")
			(clearance -0.070866)
		)
		(pad "P1_1" thru_hole circle
			(at 0 -25.4 270)
			(size 1.669796 1.669796)
			(drill 1.01981)
			(layers "*.Cu" "*.Mask")
			(remove_unused_layers no)
			(net "GND")
			(clearance -0.070866)
		)
		(pad "P1_2" thru_hole circle
			(at 2.54 -25.4 270)
			(size 1.669796 1.669796)
			(drill 1.01981)
			(layers "*.Cu" "*.Mask")
			(remove_unused_layers no)
			(net "GND")
			(clearance -0.070866)
		)
		(pad "P1_3" thru_hole circle
			(at 5.08 -25.4 270)
			(size 1.669796 1.669796)
			(drill 1.01981)
			(layers "*.Cu" "*.Mask")
			(remove_unused_layers no)
			(net "GND")
			(clearance -0.070866)
		)
		(pad "P1_4" thru_hole circle
			(at 7.62 -25.4 270)
			(size 1.669796 1.669796)
			(drill 1.01981)
			(layers "*.Cu" "*.Mask")
			(remove_unused_layers no)
			(net "GND")
			(clearance -0.070866)
		)
		(pad "P1_5" thru_hole circle
			(at 0 -22.86 270)
			(size 1.669796 1.669796)
			(drill 1.01981)
			(layers "*.Cu" "*.Mask")
			(remove_unused_layers no)
			(net "GND")
			(clearance -0.070866)
		)
		(pad "P1_6" thru_hole circle
			(at 2.54 -22.86 270)
			(size 1.669796 1.669796)
			(drill 1.01981)
			(layers "*.Cu" "*.Mask")
			(remove_unused_layers no)
			(net "GND")
			(clearance -0.070866)
		)
		(pad "P1_7" thru_hole circle
			(at 5.08 -22.86 270)
			(size 1.669796 1.669796)
			(drill 1.01981)
			(layers "*.Cu" "*.Mask")
			(remove_unused_layers no)
			(net "GND")
			(clearance -0.070866)
		)
		(pad "P1_8" thru_hole circle
			(at 7.62 -22.86 270)
			(size 1.669796 1.669796)
			(drill 1.01981)
			(layers "*.Cu" "*.Mask")
			(remove_unused_layers no)
			(net "GND")
			(clearance -0.070866)
		)
		(pad "P2_1" thru_hole circle
			(at 0 -16.51 270)
			(size 1.669796 1.669796)
			(drill 1.01981)
			(layers "*.Cu" "*.Mask")
			(remove_unused_layers no)
			(net "GND")
			(clearance -0.070866)
		)
		(pad "P2_2" thru_hole circle
			(at 2.54 -16.51 270)
			(size 1.669796 1.669796)
			(drill 1.01981)
			(layers "*.Cu" "*.Mask")
			(remove_unused_layers no)
			(net "GND")
			(clearance -0.070866)
		)
		(pad "P2_3" thru_hole circle
			(at 5.08 -16.51 270)
			(size 1.669796 1.669796)
			(drill 1.01981)
			(layers "*.Cu" "*.Mask")
			(remove_unused_layers no)
			(net "GND")
			(clearance -0.070866)
		)
		(pad "P2_4" thru_hole circle
			(at 7.62 -16.51 270)
			(size 1.669796 1.669796)
			(drill 1.01981)
			(layers "*.Cu" "*.Mask")
			(remove_unused_layers no)
			(net "GND")
			(clearance -0.070866)
		)
		(pad "P2_5" thru_hole circle
			(at 0 -13.97 270)
			(size 1.669796 1.669796)
			(drill 1.01981)
			(layers "*.Cu" "*.Mask")
			(remove_unused_layers no)
			(net "GND")
			(clearance -0.070866)
		)
		(pad "P2_6" thru_hole circle
			(at 2.54 -13.97 270)
			(size 1.669796 1.669796)
			(drill 1.01981)
			(layers "*.Cu" "*.Mask")
			(remove_unused_layers no)
			(net "GND")
			(clearance -0.070866)
		)
		(pad "P2_7" thru_hole circle
			(at 5.08 -13.97 270)
			(size 1.669796 1.669796)
			(drill 1.01981)
			(layers "*.Cu" "*.Mask")
			(remove_unused_layers no)
			(net "GND")
			(clearance -0.070866)
		)
		(pad "P2_8" thru_hole circle
			(at 7.62 -13.97 270)
			(size 1.669796 1.669796)
			(drill 1.01981)
			(layers "*.Cu" "*.Mask")
			(remove_unused_layers no)
			(net "GND")
			(clearance -0.070866)
		)
		(pad "P3_1" thru_hole circle
			(at 0 -7.62 270)
			(size 1.669796 1.669796)
			(drill 1.01981)
			(layers "*.Cu" "*.Mask")
			(remove_unused_layers no)
			(net "GND")
			(clearance -0.070866)
		)
		(pad "P3_2" thru_hole circle
			(at 2.54 -7.62 270)
			(size 1.669796 1.669796)
			(drill 1.01981)
			(layers "*.Cu" "*.Mask")
			(remove_unused_layers no)
			(net "GND")
			(clearance -0.070866)
		)
		(pad "P3_3" thru_hole circle
			(at 5.08 -7.62 270)
			(size 1.669796 1.669796)
			(drill 1.01981)
			(layers "*.Cu" "*.Mask")
			(remove_unused_layers no)
			(net "GND")
			(clearance -0.070866)
		)
		(pad "P3_4" thru_hole circle
			(at 7.62 -7.62 270)
			(size 1.669796 1.669796)
			(drill 1.01981)
			(layers "*.Cu" "*.Mask")
			(remove_unused_layers no)
			(net "GND")
			(clearance -0.070866)
		)
		(pad "P3_5" thru_hole circle
			(at 0 -5.08 270)
			(size 1.669796 1.669796)
			(drill 1.01981)
			(layers "*.Cu" "*.Mask")
			(remove_unused_layers no)
			(net "GND")
			(clearance -0.070866)
		)
		(pad "P3_6" thru_hole circle
			(at 2.54 -5.08 270)
			(size 1.669796 1.669796)
			(drill 1.01981)
			(layers "*.Cu" "*.Mask")
			(remove_unused_layers no)
			(net "GND")
			(clearance -0.070866)
		)
		(pad "P3_7" thru_hole circle
			(at 5.08 -5.08 270)
			(size 1.669796 1.669796)
			(drill 1.01981)
			(layers "*.Cu" "*.Mask")
			(remove_unused_layers no)
			(net "GND")
			(clearance -0.070866)
		)
		(pad "P3_8" thru_hole circle
			(at 7.62 -5.08 270)
			(size 1.669796 1.669796)
			(drill 1.01981)
			(layers "*.Cu" "*.Mask")
			(remove_unused_layers no)
			(net "GND")
			(clearance -0.070866)
		)
		(pad "P4_1" thru_hole circle
			(at 0 10.16 270)
			(size 1.669796 1.669796)
			(drill 1.01981)
			(layers "*.Cu" "*.Mask")
			(remove_unused_layers no)
			(net "P12V_PSU")
			(clearance -0.070866)
		)
		(pad "P4_2" thru_hole circle
			(at 2.54 10.16 270)
			(size 1.669796 1.669796)
			(drill 1.01981)
			(layers "*.Cu" "*.Mask")
			(remove_unused_layers no)
			(net "P12V_PSU")
			(clearance -0.070866)
		)
		(pad "P4_3" thru_hole circle
			(at 5.08 10.16 270)
			(size 1.669796 1.669796)
			(drill 1.01981)
			(layers "*.Cu" "*.Mask")
			(remove_unused_layers no)
			(net "P12V_PSU")
			(clearance -0.070866)
		)
		(pad "P4_4" thru_hole circle
			(at 7.62 10.16 270)
			(size 1.669796 1.669796)
			(drill 1.01981)
			(layers "*.Cu" "*.Mask")
			(remove_unused_layers no)
			(net "P12V_PSU")
			(clearance -0.070866)
		)
		(pad "P4_5" thru_hole circle
			(at 0 12.7 270)
			(size 1.669796 1.669796)
			(drill 1.01981)
			(layers "*.Cu" "*.Mask")
			(remove_unused_layers no)
			(net "P12V_PSU")
			(clearance -0.070866)
		)
		(pad "P4_6" thru_hole circle
			(at 2.54 12.7 270)
			(size 1.669796 1.669796)
			(drill 1.01981)
			(layers "*.Cu" "*.Mask")
			(remove_unused_layers no)
			(net "P12V_PSU")
			(clearance -0.070866)
		)
		(pad "P4_7" thru_hole circle
			(at 5.08 12.7 270)
			(size 1.669796 1.669796)
			(drill 1.01981)
			(layers "*.Cu" "*.Mask")
			(remove_unused_layers no)
			(net "P12V_PSU")
			(clearance -0.070866)
		)
		(pad "P4_8" thru_hole circle
			(at 7.62 12.7 270)
			(size 1.669796 1.669796)
			(drill 1.01981)
			(layers "*.Cu" "*.Mask")
			(remove_unused_layers no)
			(net "P12V_PSU")
			(clearance -0.070866)
		)
		(pad "P5_1" thru_hole circle
			(at 0 19.05 270)
			(size 1.669796 1.669796)
			(drill 1.01981)
			(layers "*.Cu" "*.Mask")
			(remove_unused_layers no)
			(net "P12V_PSU")
			(clearance -0.070866)
		)
		(pad "P5_2" thru_hole circle
			(at 2.54 19.05 270)
			(size 1.669796 1.669796)
			(drill 1.01981)
			(layers "*.Cu" "*.Mask")
			(remove_unused_layers no)
			(net "P12V_PSU")
			(clearance -0.070866)
		)
		(pad "P5_3" thru_hole circle
			(at 5.08 19.05 270)
			(size 1.669796 1.669796)
			(drill 1.01981)
			(layers "*.Cu" "*.Mask")
			(remove_unused_layers no)
			(net "P12V_PSU")
			(clearance -0.070866)
		)
		(pad "P5_4" thru_hole circle
			(at 7.62 19.05 270)
			(size 1.669796 1.669796)
			(drill 1.01981)
			(layers "*.Cu" "*.Mask")
			(remove_unused_layers no)
			(net "P12V_PSU")
			(clearance -0.070866)
		)
		(pad "P5_5" thru_hole circle
			(at 0 21.59 270)
			(size 1.669796 1.669796)
			(drill 1.01981)
			(layers "*.Cu" "*.Mask")
			(remove_unused_layers no)
			(net "P12V_PSU")
			(clearance -0.070866)
		)
		(pad "P5_6" thru_hole circle
			(at 2.54 21.59 270)
			(size 1.669796 1.669796)
			(drill 1.01981)
			(layers "*.Cu" "*.Mask")
			(remove_unused_layers no)
			(net "P12V_PSU")
			(clearance -0.070866)
		)
		(pad "P5_7" thru_hole circle
			(at 5.08 21.59 270)
			(size 1.669796 1.669796)
			(drill 1.01981)
			(layers "*.Cu" "*.Mask")
			(remove_unused_layers no)
			(net "P12V_PSU")
			(clearance -0.070866)
		)
		(pad "P5_8" thru_hole circle
			(at 7.62 21.59 270)
			(size 1.669796 1.669796)
			(drill 1.01981)
			(layers "*.Cu" "*.Mask")
			(remove_unused_layers no)
			(net "P12V_PSU")
			(clearance -0.070866)
		)
		(pad "P6_1" thru_hole circle
			(at 0 27.94 270)
			(size 1.669796 1.669796)
			(drill 1.01981)
			(layers "*.Cu" "*.Mask")
			(remove_unused_layers no)
			(net "P12V_PSU")
			(clearance -0.070866)
		)
		(pad "P6_2" thru_hole circle
			(at 2.54 27.94 270)
			(size 1.669796 1.669796)
			(drill 1.01981)
			(layers "*.Cu" "*.Mask")
			(remove_unused_layers no)
			(net "P12V_PSU")
			(clearance -0.070866)
		)
		(pad "P6_3" thru_hole circle
			(at 5.08 27.94 270)
			(size 1.669796 1.669796)
			(drill 1.01981)
			(layers "*.Cu" "*.Mask")
			(remove_unused_layers no)
			(net "P12V_PSU")
			(clearance -0.070866)
		)
		(pad "P6_4" thru_hole circle
			(at 7.62 27.94 270)
			(size 1.669796 1.669796)
			(drill 1.01981)
			(layers "*.Cu" "*.Mask")
			(remove_unused_layers no)
			(net "P12V_PSU")
			(clearance -0.070866)
		)
		(pad "P6_5" thru_hole circle
			(at 0 30.48 270)
			(size 1.669796 1.669796)
			(drill 1.01981)
			(layers "*.Cu" "*.Mask")
			(remove_unused_layers no)
			(net "P12V_PSU")
			(clearance -0.070866)
		)
		(pad "P6_6" thru_hole circle
			(at 2.54 30.48 270)
			(size 1.669796 1.669796)
			(drill 1.01981)
			(layers "*.Cu" "*.Mask")
			(remove_unused_layers no)
			(net "P12V_PSU")
			(clearance -0.070866)
		)
		(pad "P6_7" thru_hole circle
			(at 5.08 30.48 270)
			(size 1.669796 1.669796)
			(drill 1.01981)
			(layers "*.Cu" "*.Mask")
			(remove_unused_layers no)
			(net "P12V_PSU")
			(clearance -0.070866)
		)
		(pad "P6_8" thru_hole circle
			(at 7.62 30.48 270)
			(size 1.669796 1.669796)
			(drill 1.01981)
			(layers "*.Cu" "*.Mask")
			(remove_unused_layers no)
			(net "P12V_PSU")
			(clearance -0.070866)
		)
	)
)
